# T6G (Grand Teton) — schematic netlist excerpt (pin names and nets, part order shuffled) for the footprints in the layout excerpt that follows; sources: Cadence DE-HDL packaged netlist, KiCad conversion of 04192023_DAF0TMB3IC0_F0TG_MB_C_brd_V02_OCP.brd

R3509  Q_RES  10K 1% CHIP  pkg 0402LF  page 130 : A = GPU_FPGA_RST_R1_BUF_N ; B = GND
PR6620  Q_RES  0 5% EMPTY  pkg 0402LF  page 365 : A = P3V3_AUX ; B = P0V9_RETIMER_CPU1_PVCC

(kicad_pcb
	(version 20260206)
	(generator "pcbnew")
	(generator_version "10.0")
	(general
		(thickness 1.6)
		(legacy_teardrops no)
	)
	(paper "A4")
	(title_block
		(title "04192023_DAF0TMB3IC0_F0TG_MB_C_brd_V02_OCP.brd")
		(comment 1 "Grand Teton / footprints 2686-2687 of 8354")
	)
	(layers
		(0 "F.Cu" signal "TOP")
		(4 "In1.Cu" signal "GND")
		(6 "In2.Cu" signal "IN1")
		(8 "In3.Cu" signal "GND1")
		(10 "In4.Cu" signal "IN2")
		(12 "In5.Cu" signal "GND2")
		(14 "In6.Cu" signal "IN3")
		(16 "In7.Cu" signal "GND3")
		(18 "In8.Cu" signal "VCC")
		(20 "In9.Cu" signal "VCC1")
		(22 "In10.Cu" signal "GND4")
		(24 "In11.Cu" signal "IN4")
		(26 "In12.Cu" signal "GND5")
		(28 "In13.Cu" signal "IN5")
		(30 "In14.Cu" signal "GND6")
		(32 "In15.Cu" signal "IN6")
		(34 "In16.Cu" signal "GND7")
		(2 "B.Cu" signal "BOTTOM")
		(9 "F.Adhes" user "F.Adhesive")
		(11 "B.Adhes" user "B.Adhesive")
		(13 "F.Paste" user "Package Geometry/Pastemask Top")
		(15 "B.Paste" user "Package Geometry/Pastemask Bottom")
		(5 "F.SilkS" user "Ref Des/Silkscreen Top")
		(7 "B.SilkS" user "Ref Des/Silkscreen Bottom")
		(1 "F.Mask" user "Board Geometry/Soldermask Top")
		(3 "B.Mask" user "Board Geometry/Soldermask Bottom")
		(17 "Dwgs.User" user "User.Drawings")
		(19 "Cmts.User" user "User.Comments")
		(21 "Eco1.User" user "User.Eco1")
		(23 "Eco2.User" user "User.Eco2")
		(25 "Edge.Cuts" user "Board Geometry/Outline")
		(27 "Margin" user)
		(31 "F.CrtYd" user "Package Geometry/Place Bound Top")
		(29 "B.CrtYd" user "Package Geometry/Place Bound Bottom")
		(35 "F.Fab" user "Ref Des/Assembly Top")
		(33 "B.Fab" user "Ref Des/Assembly Bottom")
	)
	(footprint ""
		(layer "F.Cu")
		(at 10.7061 -394.22832 -90)
		(property "Reference" "PR6620"
			(at 0 0 270)
			(layer "F.SilkS")
			(hide yes)
			(effects
				(font
					(size 1.27 1.27)
				)
			)
		)
		(property "Value" ""
			(at 0 0 270)
			(layer "F.Fab")
			(effects
				(font
					(size 1.27 1.27)
				)
			)
		)
		(duplicate_pad_numbers_are_jumpers no)
		(fp_line
			(start -0.7874 0.4064)
			(end -0.7874 -0.4064)
			(stroke
				(width 0.1524)
				(type default)
			)
			(layer "F.SilkS")
		)
		(fp_line
			(start 0.7874 0.4064)
			(end -0.7874 0.4064)
			(stroke
				(width 0.1524)
				(type default)
			)
			(layer "F.SilkS")
		)
		(fp_line
			(start -0.7874 -0.4064)
			(end 0.7874 -0.4064)
			(stroke
				(width 0.1524)
				(type default)
			)
			(layer "F.SilkS")
		)
		(fp_line
			(start 0.7874 -0.4064)
			(end 0.7874 0.4064)
			(stroke
				(width 0.1524)
				(type default)
			)
			(layer "F.SilkS")
		)
		(fp_line
			(start -0.67945 0.3048)
			(end -0.67945 -0.305054)
			(stroke
				(width 0.1)
				(type default)
			)
			(layer "F.Fab")
		)
		(fp_line
			(start -0.12065 0.3048)
			(end -0.67945 0.3048)
			(stroke
				(width 0.1)
				(type default)
			)
			(layer "F.Fab")
		)
		(fp_line
			(start 0.120396 0.3048)
			(end 0.120396 0.2794)
			(stroke
				(width 0.1)
				(type default)
			)
			(layer "F.Fab")
		)
		(fp_line
			(start 0.67945 0.3048)
			(end 0.120396 0.3048)
			(stroke
				(width 0.1)
				(type default)
			)
			(layer "F.Fab")
		)
		(fp_line
			(start -0.12065 0.2794)
			(end -0.12065 0.3048)
			(stroke
				(width 0.1)
				(type default)
			)
			(layer "F.Fab")
		)
		(fp_line
			(start 0.120396 0.2794)
			(end -0.12065 0.2794)
			(stroke
				(width 0.1)
				(type default)
			)
			(layer "F.Fab")
		)
		(fp_line
			(start -0.12065 -0.2794)
			(end 0.12065 -0.2794)
			(stroke
				(width 0.1)
				(type default)
			)
			(layer "F.Fab")
		)
		(fp_line
			(start 0.12065 -0.2794)
			(end 0.12065 -0.3048)
			(stroke
				(width 0.1)
				(type default)
			)
			(layer "F.Fab")
		)
		(fp_line
			(start 0.12065 -0.3048)
			(end 0.67945 -0.3048)
			(stroke
				(width 0.1)
				(type default)
			)
			(layer "F.Fab")
		)
		(fp_line
			(start 0.67945 -0.3048)
			(end 0.67945 0.3048)
			(stroke
				(width 0.1)
				(type default)
			)
			(layer "F.Fab")
		)
		(fp_line
			(start -0.67945 -0.305054)
			(end -0.12065 -0.305054)
			(stroke
				(width 0.1)
				(type default)
			)
			(layer "F.Fab")
		)
		(fp_line
			(start -0.12065 -0.305054)
			(end -0.12065 -0.2794)
			(stroke
				(width 0.1)
				(type default)
			)
			(layer "F.Fab")
		)
		(pad "1" smd circle
			(at -0.40005 0 270)
			(size 0 0)
			(layers "F.Cu" "F.Mask" "F.Paste")
			(net "P3V3_AUX")
		)
		(pad "2" smd circle
			(at 0.40005 0 270)
			(size 0 0)
			(layers "F.Cu" "F.Mask" "F.Paste")
			(net "P0V9_RETIMER_CPU1_PVCC")
		)
	)
	(footprint ""
		(layer "F.Cu")
		(at 46.16704 -434.057552 -90)
		(property "Reference" "R3509"
			(at 0 0 270)
			(layer "F.SilkS")
			(hide yes)
			(effects
				(font
					(size 1.27 1.27)
				)
			)
		)
		(property "Value" ""
			(at 0 0 270)
			(layer "F.Fab")
			(effects
				(font
					(size 1.27 1.27)
				)
			)
		)
		(duplicate_pad_numbers_are_jumpers no)
		(fp_line
			(start -0.7874 0.4064)
			(end -0.7874 -0.4064)
			(stroke
				(width 0.1524)
				(type default)
			)
			(layer "F.SilkS")
		)
		(fp_line
			(start 0.7874 0.4064)
			(end -0.7874 0.4064)
			(stroke
				(width 0.1524)
				(type default)
			)
			(layer "F.SilkS")
		)
		(fp_line
			(start -0.7874 -0.4064)
			(end 0.7874 -0.4064)
			(stroke
				(width 0.1524)
				(type default)
			)
			(layer "F.SilkS")
		)
		(fp_line
			(start 0.7874 -0.4064)
			(end 0.7874 0.4064)
			(stroke
				(width 0.1524)
				(type default)
			)
			(layer "F.SilkS")
		)
		(fp_line
			(start -0.67945 0.3048)
			(end -0.67945 -0.305054)
			(stroke
				(width 0.1)
				(type default)
			)
			(layer "F.Fab")
		)
		(fp_line
			(start -0.12065 0.3048)
			(end -0.67945 0.3048)
			(stroke
				(width 0.1)
				(type default)
			)
			(layer "F.Fab")
		)
		(fp_line
			(start 0.120396 0.3048)
			(end 0.120396 0.2794)
			(stroke
				(width 0.1)
				(type default)
			)
			(layer "F.Fab")
		)
		(fp_line
			(start 0.67945 0.3048)
			(end 0.120396 0.3048)
			(stroke
				(width 0.1)
				(type default)
			)
			(layer "F.Fab")
		)
		(fp_line
			(start -0.12065 0.2794)
			(end -0.12065 0.3048)
			(stroke
				(width 0.1)
				(type default)
			)
			(layer "F.Fab")
		)
		(fp_line
			(start 0.120396 0.2794)
			(end -0.12065 0.2794)
			(stroke
				(width 0.1)
				(type default)
			)
			(layer "F.Fab")
		)
		(fp_line
			(start -0.12065 -0.2794)
			(end 0.12065 -0.2794)
			(stroke
				(width 0.1)
				(type default)
			)
			(layer "F.Fab")
		)
		(fp_line
			(start 0.12065 -0.2794)
			(end 0.12065 -0.3048)
			(stroke
				(width 0.1)
				(type default)
			)
			(layer "F.Fab")
		)
		(fp_line
			(start 0.12065 -0.3048)
			(end 0.67945 -0.3048)
			(stroke
				(width 0.1)
				(type default)
			)
			(layer "F.Fab")
		)
		(fp_line
			(start 0.67945 -0.3048)
			(end 0.67945 0.3048)
			(stroke
				(width 0.1)
				(type default)
			)
			(layer "F.Fab")
		)
		(fp_line
			(start -0.67945 -0.305054)
			(end -0.12065 -0.305054)
			(stroke
				(width 0.1)
				(type default)
			)
			(layer "F.Fab")
		)
		(fp_line
			(start -0.12065 -0.305054)
			(end -0.12065 -0.2794)
			(stroke
				(width 0.1)
				(type default)
			)
			(layer "F.Fab")
		)
		(pad "1" smd circle
			(at -0.40005 0 270)
			(size 0 0)
			(layers "F.Cu" "F.Mask" "F.Paste")
			(net "GPU_FPGA_RST_R1_BUF_N")
		)
		(pad "2" smd circle
			(at 0.40005 0 270)
			(size 0 0)
			(layers "F.Cu" "F.Mask" "F.Paste")
			(net "GND")
		)
	)
)
